(kicad_pcb
	(version 20241229)
	(generator "pcbnew")
	(generator_version "9.0")
	(general
		(thickness 1.711)
		(legacy_teardrops no)
	)
	(paper "A4")
	(title_block
		(title "Antmicro Baseboard for Jetson AGX Thor")
		(date "2026-02-18")
		(rev "1.1.0")
		(company "Antmicro Ltd")
		(comment 1 "www.antmicro.com")
		(comment 9 "footprints 178-182 of 1170")
	)
	(layers
		(0 "F.Cu" signal)
		(4 "In1.Cu" signal)
		(6 "In2.Cu" signal)
		(8 "In3.Cu" signal)
		(10 "In4.Cu" jumper)
		(12 "In5.Cu" signal)
		(14 "In6.Cu" signal)
		(16 "In7.Cu" signal)
		(18 "In8.Cu" signal)
		(2 "B.Cu" signal)
		(9 "F.Adhes" user "F.Adhesive")
		(11 "B.Adhes" user "B.Adhesive")
		(13 "F.Paste" user)
		(15 "B.Paste" user)
		(5 "F.SilkS" user "F.Silkscreen")
		(7 "B.SilkS" user "B.Silkscreen")
		(1 "F.Mask" user)
		(3 "B.Mask" user)
		(17 "Dwgs.User" user "User.Drawings")
		(19 "Cmts.User" user "User.Comments")
		(21 "Eco1.User" user "User.Eco1")
		(23 "Eco2.User" user "User.Eco2")
		(25 "Edge.Cuts" user)
		(27 "Margin" user)
		(31 "F.CrtYd" user "F.Courtyard")
		(29 "B.CrtYd" user "B.Courtyard")
		(35 "F.Fab" user)
		(33 "B.Fab" user)
	)
	(footprint "antmicro-footprints:XDFN-2_1x0.60mm"
		(layer "F.Cu")
		(at 203.248 55.497999 -90)
		(property "Reference" "D46"
			(at 1.002001 0.498 90)
			(layer "F.SilkS")
			(effects
				(font
					(size 0.7 0.7)
					(thickness 0.15)
				)
				(justify left bottom)
			)
		)
		(property "Value" "TPD1E0B04_XDFN-2"
			(at 0 1.5 90)
			(layer "F.Fab")
			(effects
				(font
					(size 0.7 0.7)
					(thickness 0.15)
				)
				(justify right top)
			)
		)
		(property "Datasheet" "https://www.ti.com/general/docs/suppproductinfo.tsp?distId=26&gotoUrl=https://www.ti.com/lit/gpn/tpd1e0b04"
			(at 0 0 90)
			(layer "F.Fab")
			(hide yes)
			(effects
				(font
					(size 1.27 1.27)
					(thickness 0.15)
				)
			)
		)
		(property "Description" "Bidirectional TVS, 8 kV,  XDFN-2, 3.6 V, 0.18 pF"
			(at 0 0 90)
			(layer "F.Fab")
			(hide yes)
			(effects
				(font
					(size 1.27 1.27)
					(thickness 0.15)
				)
			)
		)
		(property "MPN" "TPD1E0B04DPYR"
			(at 0 0 90)
			(layer "F.Fab")
			(hide yes)
			(effects
				(font
					(size 1.27 1.27)
					(thickness 0.15)
				)
			)
		)
		(property "Manufacturer" "Texas Instruments"
			(at 0 0 90)
			(layer "F.Fab")
			(hide yes)
			(effects
				(font
					(size 1.27 1.27)
					(thickness 0.15)
				)
			)
		)
		(property "Author" "Antmicro"
			(at 0 0 270)
			(unlocked yes)
			(layer "F.Fab")
			(hide yes)
			(effects
				(font
					(size 1 1)
					(thickness 0.15)
				)
			)
		)
		(property "License" "Apache-2.0"
			(at 0 0 270)
			(unlocked yes)
			(layer "F.Fab")
			(hide yes)
			(effects
				(font
					(size 1 1)
					(thickness 0.15)
				)
			)
		)
		(sheetname "/SoM_Power/")
		(sheetfile "som_power.kicad_sch")
		(attr smd)
		(fp_poly
			(pts
				(xy -0.725 -0.475) (xy 0.725 -0.475) (xy 0.725 0.475) (xy -0.725 0.475)
			)
			(stroke
				(width 0.05)
				(type solid)
			)
			(fill no)
			(layer "F.CrtYd")
		)
		(fp_poly
			(pts
				(xy -0.55 -0.35) (xy 0.55 -0.35) (xy 0.55 0.35) (xy -0.55 0.35)
			)
			(stroke
				(width 0.15)
				(type solid)
			)
			(fill no)
			(layer "F.Fab")
		)
		(fp_text user "License: Apache-2.0"
			(at -0.799999 5.6 90)
			(layer "F.Fab")
			(effects
				(font
					(size 0.7 0.7)
					(thickness 0.15)
				)
				(justify right top)
			)
		)
		(fp_text user "${REFERENCE}"
			(at -0.8 3.2 90)
			(layer "F.Fab")
			(effects
				(font
					(size 0.7 0.7)
					(thickness 0.15)
				)
				(justify right top)
			)
		)
		(fp_text user "Author: Antmicro"
			(at -0.8 4.4 90)
			(layer "F.Fab")
			(effects
				(font
					(size 0.7 0.7)
					(thickness 0.15)
				)
				(justify right top)
			)
		)
		(pad "1" smd roundrect
			(at -0.350999 0 270)
			(size 0.3 0.5)
			(layers "F.Cu" "F.Mask" "F.Paste")
			(roundrect_rratio 0.25)
			(net 1 "GND")
			(pinfunction "C")
			(pintype "passive")
		)
		(pad "2" smd roundrect
			(at 0.349 0 270)
			(size 0.3 0.5)
			(layers "F.Cu" "F.Mask" "F.Paste")
			(roundrect_rratio 0.25)
			(net 495 "/SoM_Power/~{FORCE_RECOVERY}")
			(pinfunction "A")
			(pintype "passive")
		)
	)
	(footprint "antmicro-footprints:C_0402_1005Metric"
		(layer "F.Cu")
		(at 192.4 128.07)
		(descr "Capacitor SMD 0402")
		(tags "capacitor SMD 0402")
		(property "Reference" "C79"
			(at -1.4 8.03 0)
			(layer "F.SilkS")
			(effects
				(font
					(size 0.7 0.7)
					(thickness 0.15)
				)
				(justify left bottom)
			)
		)
		(property "Value" "C_100n_0402"
			(at -1.022927 2.155213 0)
			(layer "F.Fab")
			(effects
				(font
					(size 0.7 0.7)
					(thickness 0.15)
				)
				(justify left bottom)
			)
		)
		(property "Datasheet" "https://www.murata.com/products/productdetail?partno=GRM155R61H104KE14%23"
			(at 0 0 0)
			(layer "F.Fab")
			(hide yes)
			(effects
				(font
					(size 1.27 1.27)
					(thickness 0.15)
				)
			)
		)
		(property "Description" "SMD Multilayer Ceramic Capacitor, 0.1 µF, 50 V, 0402 [1005 Metric], ± 10%, X5R, GRM Series"
			(at 0 0 0)
			(layer "F.Fab")
			(hide yes)
			(effects
				(font
					(size 1.27 1.27)
					(thickness 0.15)
				)
			)
		)
		(property "MPN" "GRM155R61H104KE14D"
			(at 0 0 0)
			(unlocked yes)
			(layer "F.Fab")
			(hide yes)
			(effects
				(font
					(size 1 1)
					(thickness 0.15)
				)
			)
		)
		(property "Manufacturer" "Murata"
			(at 0 0 0)
			(unlocked yes)
			(layer "F.Fab")
			(hide yes)
			(effects
				(font
					(size 1 1)
					(thickness 0.15)
				)
			)
		)
		(property "License" "Apache-2.0"
			(at 0 0 0)
			(unlocked yes)
			(layer "F.Fab")
			(hide yes)
			(effects
				(font
					(size 1 1)
					(thickness 0.15)
				)
			)
		)
		(property "Author" "Antmicro"
			(at 0 0 0)
			(unlocked yes)
			(layer "F.Fab")
			(hide yes)
			(effects
				(font
					(size 1 1)
					(thickness 0.15)
				)
			)
		)
		(property "Val" "100n"
			(at 0 0 0)
			(unlocked yes)
			(layer "F.Fab")
			(hide yes)
			(effects
				(font
					(size 1 1)
					(thickness 0.15)
				)
			)
		)
		(property "Voltage" "50V"
			(at 0 0 0)
			(unlocked yes)
			(layer "F.Fab")
			(hide yes)
			(effects
				(font
					(size 1 1)
					(thickness 0.15)
				)
			)
		)
		(property "Dielectric" "X5R"
			(at 0 0 0)
			(unlocked yes)
			(layer "F.Fab")
			(hide yes)
			(effects
				(font
					(size 1 1)
					(thickness 0.15)
				)
			)
		)
		(component_classes
			(class "DCDC_1V15")
		)
		(sheetname "/DCDC/")
		(sheetfile "dcdc.kicad_sch")
		(attr smd)
		(fp_rect
			(start -0.925 -0.47)
			(end 0.925 0.47)
			(stroke
				(width 0.05)
				(type default)
			)
			(fill no)
			(layer "F.CrtYd")
		)
		(fp_line
			(start -0.494 -0.25)
			(end 0.504 -0.25)
			(stroke
				(width 0.15)
				(type solid)
			)
			(layer "F.Fab")
		)
		(fp_line
			(start -0.494 0.248)
			(end -0.494 -0.25)
			(stroke
				(width 0.15)
				(type solid)
			)
			(layer "F.Fab")
		)
		(fp_line
			(start 0.504 -0.25)
			(end 0.504 0.248)
			(stroke
				(width 0.15)
				(type solid)
			)
			(layer "F.Fab")
		)
		(fp_line
			(start 0.504 0.248)
			(end -0.494 0.248)
			(stroke
				(width 0.15)
				(type solid)
			)
			(layer "F.Fab")
		)
		(fp_text user "${REFERENCE}"
			(at -0.939 4.599 0)
			(layer "F.Fab")
			(effects
				(font
					(size 0.7 0.7)
					(thickness 0.15)
				)
				(justify left bottom)
			)
		)
		(fp_text user "Author: Antmicro"
			(at -0.939 3.399 0)
			(layer "F.Fab")
			(effects
				(font
					(size 0.7 0.7)
					(thickness 0.15)
				)
				(justify left bottom)
			)
		)
		(fp_text user "License: Apache-2.0"
			(at -0.939 5.799 0)
			(layer "F.Fab")
			(effects
				(font
					(size 0.7 0.7)
					(thickness 0.15)
				)
				(justify left bottom)
			)
		)
		(pad "1" smd roundrect
			(at -0.48 0)
			(size 0.59 0.64)
			(layers "F.Cu" "F.Mask" "F.Paste")
			(roundrect_rratio 0.25)
			(net 1 "GND")
			(pintype "passive")
		)
		(pad "2" smd roundrect
			(at 0.48 0)
			(size 0.59 0.64)
			(layers "F.Cu" "F.Mask" "F.Paste")
			(roundrect_rratio 0.25)
			(net 280 "/DCDC/1V15_OUT")
			(pintype "passive")
		)
	)
	(footprint "antmicro-footprints:C_0402_1005Metric"
		(layer "F.Cu")
		(at 199.27 84 -90)
		(descr "Capacitor SMD 0402")
		(tags "capacitor SMD 0402")
		(property "Reference" "C139"
			(at -1.3 -0.63 90)
			(layer "F.SilkS")
			(effects
				(font
					(size 0.7 0.7)
					(thickness 0.15)
				)
				(justify right top)
			)
		)
		(property "Value" "C_10u_0402"
			(at -1.022927 2.155213 90)
			(layer "F.Fab")
			(effects
				(font
					(size 0.7 0.7)
					(thickness 0.15)
				)
				(justify right top)
			)
		)
		(property "Datasheet" "https://www.yageo.com/en/Chart/Download/pdf/CC0402MRX5R5BB106"
			(at 0 0 90)
			(layer "F.Fab")
			(hide yes)
			(effects
				(font
					(size 1.27 1.27)
					(thickness 0.15)
				)
			)
		)
		(property "Description" "SMD Multilayer Ceramic Capacitor, 10 µF, 6.3 V, 0402 [1005 Metric], ± 20%, X5R, CC Series"
			(at 0 0 90)
			(layer "F.Fab")
			(hide yes)
			(effects
				(font
					(size 1.27 1.27)
					(thickness 0.15)
				)
			)
		)
		(property "MPN" "CC0402MRX5R5BB106"
			(at 0 0 270)
			(unlocked yes)
			(layer "F.Fab")
			(hide yes)
			(effects
				(font
					(size 1 1)
					(thickness 0.15)
				)
			)
		)
		(property "Manufacturer" "YAGEO"
			(at 0 0 270)
			(unlocked yes)
			(layer "F.Fab")
			(hide yes)
			(effects
				(font
					(size 1 1)
					(thickness 0.15)
				)
			)
		)
		(property "License" "Apache-2.0"
			(at 0 0 270)
			(unlocked yes)
			(layer "F.Fab")
			(hide yes)
			(effects
				(font
					(size 1 1)
					(thickness 0.15)
				)
			)
		)
		(property "Author" "Antmicro"
			(at 0 0 270)
			(unlocked yes)
			(layer "F.Fab")
			(hide yes)
			(effects
				(font
					(size 1 1)
					(thickness 0.15)
				)
			)
		)
		(property "Val" "10u"
			(at 0 0 270)
			(unlocked yes)
			(layer "F.Fab")
			(hide yes)
			(effects
				(font
					(size 1 1)
					(thickness 0.15)
				)
			)
		)
		(property "Voltage" ""
			(at 0 0 270)
			(unlocked yes)
			(layer "F.Fab")
			(hide yes)
			(effects
				(font
					(size 1 1)
					(thickness 0.15)
				)
			)
		)
		(property "Dielectric" ""
			(at 0 0 270)
			(unlocked yes)
			(layer "F.Fab")
			(hide yes)
			(effects
				(font
					(size 1 1)
					(thickness 0.15)
				)
			)
		)
		(sheetname "/USB DP Alt mode/")
		(sheetfile "usb_dp.kicad_sch")
		(attr smd)
		(fp_rect
			(start -0.925 -0.47)
			(end 0.925 0.47)
			(stroke
				(width 0.05)
				(type default)
			)
			(fill no)
			(layer "F.CrtYd")
		)
		(fp_line
			(start -0.494 0.248)
			(end -0.494 -0.25)
			(stroke
				(width 0.15)
				(type solid)
			)
			(layer "F.Fab")
		)
		(fp_line
			(start 0.504 0.248)
			(end -0.494 0.248)
			(stroke
				(width 0.15)
				(type solid)
			)
			(layer "F.Fab")
		)
		(fp_line
			(start -0.494 -0.25)
			(end 0.504 -0.25)
			(stroke
				(width 0.15)
				(type solid)
			)
			(layer "F.Fab")
		)
		(fp_line
			(start 0.504 -0.25)
			(end 0.504 0.248)
			(stroke
				(width 0.15)
				(type solid)
			)
			(layer "F.Fab")
		)
		(fp_text user "${REFERENCE}"
			(at -0.939 4.599 90)
			(layer "F.Fab")
			(effects
				(font
					(size 0.7 0.7)
					(thickness 0.15)
				)
				(justify right top)
			)
		)
		(fp_text user "Author: Antmicro"
			(at -0.939 3.399 90)
			(layer "F.Fab")
			(effects
				(font
					(size 0.7 0.7)
					(thickness 0.15)
				)
				(justify right top)
			)
		)
		(fp_text user "License: Apache-2.0"
			(at -0.939 5.799 90)
			(layer "F.Fab")
			(effects
				(font
					(size 0.7 0.7)
					(thickness 0.15)
				)
				(justify right top)
			)
		)
		(pad "1" smd roundrect
			(at -0.48 0 270)
			(size 0.59 0.64)
			(layers "F.Cu" "F.Mask" "F.Paste")
			(roundrect_rratio 0.25)
			(net 5 "+5V")
			(pintype "passive")
		)
		(pad "2" smd roundrect
			(at 0.48 0 270)
			(size 0.59 0.64)
			(layers "F.Cu" "F.Mask" "F.Paste")
			(roundrect_rratio 0.25)
			(net 1 "GND")
			(pintype "passive")
		)
	)
	(footprint "antmicro-footprints:TP_SMD_0.75mm"
		(layer "F.Cu")
		(at 181 60.5 90)
		(property "Reference" "TP3"
			(at -1.15 -0.75 90)
			(layer "F.SilkS")
			(hide yes)
			(effects
				(font
					(size 0.7 0.7)
					(thickness 0.15)
				)
				(justify left bottom)
			)
		)
		(property "Value" "TP_0.75mm_SMD"
			(at 0 1.2 90)
			(layer "F.Fab")
			(effects
				(font
					(size 0.7 0.7)
					(thickness 0.15)
				)
				(justify left bottom)
			)
		)
		(property "Description" "SMT test point"
			(at 0 0 90)
			(layer "F.Fab")
			(hide yes)
			(effects
				(font
					(size 1.27 1.27)
					(thickness 0.15)
				)
			)
		)
		(property "MPN" ""
			(at 0 0 90)
			(unlocked yes)
			(layer "F.Fab")
			(hide yes)
			(effects
				(font
					(size 1 1)
					(thickness 0.15)
				)
			)
		)
		(property "Manufacturer" ""
			(at 0 0 90)
			(unlocked yes)
			(layer "F.Fab")
			(hide yes)
			(effects
				(font
					(size 1 1)
					(thickness 0.15)
				)
			)
		)
		(property "Author" "Antmicro"
			(at 0 0 90)
			(unlocked yes)
			(layer "F.Fab")
			(hide yes)
			(effects
				(font
					(size 1 1)
					(thickness 0.15)
				)
			)
		)
		(property "License" "Apache-2.0"
			(at 0 0 90)
			(unlocked yes)
			(layer "F.Fab")
			(hide yes)
			(effects
				(font
					(size 1 1)
					(thickness 0.15)
				)
			)
		)
		(sheetname "/Power/")
		(sheetfile "power.kicad_sch")
		(attr exclude_from_pos_files exclude_from_bom)
		(fp_circle
			(center 0 0)
			(end 0.475 0)
			(stroke
				(width 0.05)
				(type default)
			)
			(fill no)
			(layer "F.CrtYd")
		)
		(fp_text user "${REFERENCE}"
			(at -0.4 2.7 90)
			(layer "F.Fab")
			(effects
				(font
					(size 0.7 0.7)
					(thickness 0.15)
				)
				(justify left bottom)
			)
		)
		(fp_text user "License: Apache-2.0"
			(at -0.4 5.101 90)
			(layer "F.Fab")
			(effects
				(font
					(size 0.7 0.7)
					(thickness 0.15)
				)
				(justify left bottom)
			)
		)
		(fp_text user "Author: Antmicro"
			(at -0.4 3.901 90)
			(layer "F.Fab")
			(effects
				(font
					(size 0.7 0.7)
					(thickness 0.15)
				)
				(justify left bottom)
			)
		)
		(pad "1" smd circle
			(at 0 0 90)
			(size 0.75 0.75)
			(layers "F.Cu" "F.Mask")
			(net 1 "GND")
			(pinfunction "1")
			(pintype "passive")
		)
	)
	(footprint "antmicro-footprints:USON-10_2.5x1mm_P0.5mm"
		(layer "F.Cu")
		(at 220.814 114.527)
		(descr "USON-10 2.5x1mm_ Pitch 0.5mm")
		(tags "USON-10 2.5x1mm Pitch 0.5mm")
		(property "Reference" "U28"
			(at 1.766 -1.857 90)
			(layer "F.SilkS")
			(effects
				(font
					(size 0.7 0.7)
					(thickness 0.15)
				)
				(justify left bottom)
			)
		)
		(property "Value" "TPD4E05U06QDQARQ1"
			(at 0.018 2.499 0)
			(layer "F.Fab")
			(effects
				(font
					(size 0.7 0.7)
					(thickness 0.15)
				)
				(justify left bottom)
			)
		)
		(property "Datasheet" "https://www.ti.com/lit/ds/symlink/tpd4e05u06-q1.pdf?HQS=dis-mous-null-mousermode-dsf-pf-null-wwe&ts=1663591265741&ref_url=https%253A%252F%252Fwww.mouser.com%252F"
			(at 0 0 0)
			(layer "F.Fab")
			(hide yes)
			(effects
				(font
					(size 1.27 1.27)
					(thickness 0.15)
				)
			)
		)
		(property "Description" "TVS diode array, 12 kV, USON-10, 5.5 V, 0.5 pF"
			(at 0 0 0)
			(layer "F.Fab")
			(hide yes)
			(effects
				(font
					(size 1.27 1.27)
					(thickness 0.15)
				)
			)
		)
		(property "Manufacturer" "Texas Instruments"
			(at 0 0 0)
			(unlocked yes)
			(layer "F.Fab")
			(hide yes)
			(effects
				(font
					(size 1 1)
					(thickness 0.15)
				)
			)
		)
		(property "MPN" "TPD4E05U06QDQARQ1"
			(at 0 0 0)
			(unlocked yes)
			(layer "F.Fab")
			(hide yes)
			(effects
				(font
					(size 1 1)
					(thickness 0.15)
				)
			)
		)
		(property "Author" "Antmicro"
			(at 0 0 0)
			(unlocked yes)
			(layer "F.Fab")
			(hide yes)
			(effects
				(font
					(size 1 1)
					(thickness 0.15)
				)
			)
		)
		(property "License" "Apache-2.0"
			(at 0 0 0)
			(unlocked yes)
			(layer "F.Fab")
			(hide yes)
			(effects
				(font
					(size 1 1)
					(thickness 0.15)
				)
			)
		)
		(sheetname "/USB Hub/")
		(sheetfile "usb_hub.kicad_sch")
		(attr smd)
		(fp_line
			(start 0.498 -1.401)
			(end -0.5 -1.401)
			(stroke
				(width 0.15)
				(type solid)
			)
			(layer "F.SilkS")
		)
		(fp_line
			(start 0.498 1.398)
			(end -0.5 1.398)
			(stroke
				(width 0.15)
				(type solid)
			)
			(layer "F.SilkS")
		)
		(fp_circle
			(center -0.68 -1.27)
			(end -0.63 -1.27)
			(stroke
				(width 0.15)
				(type solid)
			)
			(fill yes)
			(layer "F.SilkS")
		)
		(fp_rect
			(start -0.8 -1.5)
			(end 0.8 1.499)
			(stroke
				(width 0.05)
				(type solid)
			)
			(fill no)
			(layer "F.CrtYd")
		)
		(fp_line
			(start -0.5 -1)
			(end -0.5 1.249)
			(stroke
				(width 0.15)
				(type solid)
			)
			(layer "F.Fab")
		)
		(fp_line
			(start -0.5 1.249)
			(end 0.498 1.249)
			(stroke
				(width 0.15)
				(type solid)
			)
			(layer "F.Fab")
		)
		(fp_line
			(start -0.25 -1.25)
			(end -0.5 -1)
			(stroke
				(width 0.15)
				(type solid)
			)
			(layer "F.Fab")
		)
		(fp_line
			(start 0.498 -1.25)
			(end -0.25 -1.25)
			(stroke
				(width 0.15)
				(type solid)
			)
			(layer "F.Fab")
		)
		(fp_line
			(start 0.498 -1.25)
			(end 0.498 1.249)
			(stroke
				(width 0.15)
				(type solid)
			)
			(layer "F.Fab")
		)
		(fp_text user "${REFERENCE}"
			(at -0.802 4.498 0)
			(layer "F.Fab")
			(effects
				(font
					(size 0.7 0.7)
					(thickness 0.15)
				)
				(justify left bottom)
			)
		)
		(fp_text user "License: Apache-2.0"
			(at -0.802 6.9 0)
			(layer "F.Fab")
			(effects
				(font
					(size 0.7 0.7)
					(thickness 0.15)
				)
				(justify left bottom)
			)
		)
		(fp_text user "Author: Antmicro"
			(at -0.802 5.7 0)
			(layer "F.Fab")
			(effects
				(font
					(size 0.7 0.7)
					(thickness 0.15)
				)
				(justify left bottom)
			)
		)
		(pad "1" smd roundrect
			(at -0.387 -1 270)
			(size 0.25 0.55)
			(layers "F.Cu" "F.Mask" "F.Paste")
			(roundrect_rratio 0.25)
			(net 508 "/USB Hub/USBC3_D-")
			(pintype "passive")
		)
		(pad "2" smd roundrect
			(at -0.387 -0.5 270)
			(size 0.25 0.55)
			(layers "F.Cu" "F.Mask" "F.Paste")
			(roundrect_rratio 0.25)
			(net 506 "/USB Hub/USBC3_D+")
			(pintype "passive")
		)
		(pad "3" smd roundrect
			(at -0.387 0 270)
			(size 0.4 0.55)
			(layers "F.Cu" "F.Mask" "F.Paste")
			(roundrect_rratio 0.25)
			(net 1 "GND")
			(pintype "power_in")
		)
		(pad "4" smd roundrect
			(at -0.387 0.498 270)
			(size 0.25 0.55)
			(layers "F.Cu" "F.Mask" "F.Paste")
			(roundrect_rratio 0.25)
			(net 509 "/USB Hub/USBC3_CC_{2}")
			(pintype "passive")
		)
		(pad "5" smd roundrect
			(at -0.387 0.998 270)
			(size 0.25 0.55)
			(layers "F.Cu" "F.Mask" "F.Paste")
			(roundrect_rratio 0.25)
			(net 510 "/USB Hub/USBC3_CC_{1}")
			(pintype "passive")
		)
		(pad "6" smd roundrect
			(at 0.385 0.998 270)
			(size 0.25 0.55)
			(layers "F.Cu" "F.Mask" "F.Paste")
			(roundrect_rratio 0.25)
			(net 510 "/USB Hub/USBC3_CC_{1}")
			(pintype "passive")
		)
		(pad "7" smd roundrect
			(at 0.385 0.498 270)
			(size 0.25 0.55)
			(layers "F.Cu" "F.Mask" "F.Paste")
			(roundrect_rratio 0.25)
			(net 509 "/USB Hub/USBC3_CC_{2}")
			(pintype "passive")
		)
		(pad "8" smd roundrect
			(at 0.385 0 270)
			(size 0.4 0.55)
			(layers "F.Cu" "F.Mask" "F.Paste")
			(roundrect_rratio 0.25)
			(net 1 "GND")
			(pintype "passive")
		)
		(pad "9" smd roundrect
			(at 0.385 -0.5 270)
			(size 0.25 0.55)
			(layers "F.Cu" "F.Mask" "F.Paste")
			(roundrect_rratio 0.25)
			(net 506 "/USB Hub/USBC3_D+")
			(pintype "passive")
		)
		(pad "10" smd roundrect
			(at 0.385 -1 270)
			(size 0.25 0.55)
			(layers "F.Cu" "F.Mask" "F.Paste")
			(roundrect_rratio 0.25)
			(net 508 "/USB Hub/USBC3_D-")
			(pintype "passive")
		)
	)
)
